(kicad_pcb
	(version 20241229)
	(generator "pcbnew")
	(generator_version "9.0")
	(general
		(thickness 1.61)
		(legacy_teardrops no)
	)
	(paper "A3")
	(title_block
		(title "SO-DIMM DDR5 Tester")
		(date "2025-11-26")
		(rev "1.3.0")
		(comment 9 "footprints 516-521 of 627")
	)
	(layers
		(0 "F.Cu" signal)
		(4 "In1.Cu" power)
		(6 "In2.Cu" mixed)
		(8 "In3.Cu" power)
		(10 "In4.Cu" mixed)
		(12 "In5.Cu" power)
		(14 "In6.Cu" mixed)
		(16 "In7.Cu" power)
		(18 "In8.Cu" power)
		(20 "In9.Cu" mixed)
		(22 "In10.Cu" power)
		(2 "B.Cu" signal)
		(9 "F.Adhes" user "F.Adhesive")
		(11 "B.Adhes" user "B.Adhesive")
		(13 "F.Paste" user)
		(15 "B.Paste" user)
		(5 "F.SilkS" user "F.Silkscreen")
		(7 "B.SilkS" user "B.Silkscreen")
		(1 "F.Mask" user)
		(3 "B.Mask" user)
		(17 "Dwgs.User" user "User.Drawings")
		(19 "Cmts.User" user "User.Comments")
		(21 "Eco1.User" user "User.Eco1")
		(23 "Eco2.User" user "User.Eco2")
		(25 "Edge.Cuts" user)
		(27 "Margin" user)
		(31 "F.CrtYd" user "F.Courtyard")
		(29 "B.CrtYd" user "B.Courtyard")
		(35 "F.Fab" user)
		(33 "B.Fab" user)
	)
	(footprint "antmicro-footprints:R_0402_1005Metric"
		(layer "B.Cu")
		(at 202.925 187.65 90)
		(descr "Resistor SMD 0402")
		(tags "resistor SMD 0402")
		(property "Reference" "R165"
			(at -1.1 0.325 270)
			(layer "B.SilkS")
			(effects
				(font
					(size 0.7 0.7)
					(thickness 0.15)
				)
				(justify left bottom mirror)
			)
		)
		(property "Value" "R_0R_0402"
			(at -1.011843 -1.772047 270)
			(layer "B.Fab")
			(effects
				(font
					(size 0.7 0.7)
					(thickness 0.15)
				)
				(justify left bottom mirror)
			)
		)
		(property "Datasheet" "https://industrial.panasonic.com/cdbs/www-data/pdf/RDA0000/AOA0000C301.pdf"
			(at 0 0 90)
			(layer "F.Fab")
			(hide yes)
			(effects
				(font
					(size 1.27 1.27)
					(thickness 0.15)
				)
			)
		)
		(property "Author" "Antmicro"
			(at 390.575 -15.275 0)
			(layer "B.Fab")
			(hide yes)
			(effects
				(font
					(size 1 1)
					(thickness 0.15)
				)
				(justify mirror)
			)
		)
		(property "Current" "1A"
			(at 390.575 -15.275 0)
			(layer "B.Fab")
			(hide yes)
			(effects
				(font
					(size 1 1)
					(thickness 0.15)
				)
				(justify mirror)
			)
		)
		(property "License" "Apache-2.0"
			(at 390.575 -15.275 0)
			(layer "B.Fab")
			(hide yes)
			(effects
				(font
					(size 1 1)
					(thickness 0.15)
				)
				(justify mirror)
			)
		)
		(property "MPN" "ERJ2GE0R00X"
			(at 390.575 -15.275 0)
			(layer "B.Fab")
			(hide yes)
			(effects
				(font
					(size 1 1)
					(thickness 0.15)
				)
				(justify mirror)
			)
		)
		(property "Manufacturer" "Panasonic"
			(at 390.575 -15.275 0)
			(layer "B.Fab")
			(hide yes)
			(effects
				(font
					(size 1 1)
					(thickness 0.15)
				)
				(justify mirror)
			)
		)
		(property "Tolerance" ""
			(at 390.575 -15.275 0)
			(layer "B.Fab")
			(hide yes)
			(effects
				(font
					(size 1 1)
					(thickness 0.15)
				)
				(justify mirror)
			)
		)
		(property "Val" "0R"
			(at 390.575 -15.275 0)
			(layer "B.Fab")
			(hide yes)
			(effects
				(font
					(size 1 1)
					(thickness 0.15)
				)
				(justify mirror)
			)
		)
		(sheetname "/Supply/")
		(sheetfile "supply.kicad_sch")
		(attr exclude_from_pos_files exclude_from_bom dnp)
		(fp_rect
			(start -0.93 0.47)
			(end 0.93 -0.47)
			(stroke
				(width 0.05)
				(type solid)
			)
			(fill no)
			(layer "B.CrtYd")
		)
		(fp_rect
			(start -0.5 0.25)
			(end 0.5 -0.25)
			(stroke
				(width 0.15)
				(type solid)
			)
			(fill no)
			(layer "B.Fab")
		)
		(pad "1" smd roundrect
			(at -0.485 0 90)
			(size 0.59 0.64)
			(layers "B.Cu" "B.Mask" "B.Paste")
			(roundrect_rratio 0.25)
			(net 1 "GND")
			(pintype "passive")
		)
		(pad "2" smd roundrect
			(at 0.485 0 90)
			(size 0.59 0.64)
			(layers "B.Cu" "B.Mask" "B.Paste")
			(roundrect_rratio 0.25)
			(net 220 "/Supply/FB4")
			(pintype "passive")
		)
	)
	(footprint "antmicro-footprints:R_0402_1005Metric"
		(layer "B.Cu")
		(at 148.55 142.4 -90)
		(descr "Resistor SMD 0402")
		(tags "resistor SMD 0402")
		(property "Reference" "R38"
			(at -3.044968 -0.354606 90)
			(layer "B.SilkS")
			(effects
				(font
					(size 0.7 0.7)
					(thickness 0.15)
				)
				(justify left bottom mirror)
			)
		)
		(property "Value" "R_0R_0402"
			(at -1.011843 -1.772047 90)
			(layer "B.Fab")
			(effects
				(font
					(size 0.7 0.7)
					(thickness 0.15)
				)
				(justify left bottom mirror)
			)
		)
		(property "Datasheet" "https://industrial.panasonic.com/cdbs/www-data/pdf/RDA0000/AOA0000C301.pdf"
			(at 0 0 270)
			(layer "F.Fab")
			(hide yes)
			(effects
				(font
					(size 1.27 1.27)
					(thickness 0.15)
				)
			)
		)
		(property "Author" "Antmicro"
			(at 6.15 290.95 0)
			(layer "B.Fab")
			(hide yes)
			(effects
				(font
					(size 1 1)
					(thickness 0.15)
				)
				(justify mirror)
			)
		)
		(property "Current" "1A"
			(at 6.15 290.95 0)
			(layer "B.Fab")
			(hide yes)
			(effects
				(font
					(size 1 1)
					(thickness 0.15)
				)
				(justify mirror)
			)
		)
		(property "License" "Apache-2.0"
			(at 6.15 290.95 0)
			(layer "B.Fab")
			(hide yes)
			(effects
				(font
					(size 1 1)
					(thickness 0.15)
				)
				(justify mirror)
			)
		)
		(property "MPN" "ERJ2GE0R00X"
			(at 6.15 290.95 0)
			(layer "B.Fab")
			(hide yes)
			(effects
				(font
					(size 1 1)
					(thickness 0.15)
				)
				(justify mirror)
			)
		)
		(property "Manufacturer" "Panasonic"
			(at 6.15 290.95 0)
			(layer "B.Fab")
			(hide yes)
			(effects
				(font
					(size 1 1)
					(thickness 0.15)
				)
				(justify mirror)
			)
		)
		(property "Tolerance" ""
			(at 6.15 290.95 0)
			(layer "B.Fab")
			(hide yes)
			(effects
				(font
					(size 1 1)
					(thickness 0.15)
				)
				(justify mirror)
			)
		)
		(property "Val" "0R"
			(at 6.15 290.95 0)
			(layer "B.Fab")
			(hide yes)
			(effects
				(font
					(size 1 1)
					(thickness 0.15)
				)
				(justify mirror)
			)
		)
		(sheetname "/DDR5 SODIMM/")
		(sheetfile "ddr5-sodimm.kicad_sch")
		(attr smd)
		(fp_rect
			(start -0.93 0.47)
			(end 0.93 -0.47)
			(stroke
				(width 0.05)
				(type solid)
			)
			(fill no)
			(layer "B.CrtYd")
		)
		(fp_rect
			(start -0.5 0.25)
			(end 0.5 -0.25)
			(stroke
				(width 0.15)
				(type solid)
			)
			(fill no)
			(layer "B.Fab")
		)
		(pad "1" smd roundrect
			(at -0.485 0 270)
			(size 0.59 0.64)
			(layers "B.Cu" "B.Mask" "B.Paste")
			(roundrect_rratio 0.25)
			(net 314 "Net-(J2C-PWR_EN)")
			(pintype "passive")
		)
		(pad "2" smd roundrect
			(at 0.485 0 270)
			(size 0.59 0.64)
			(layers "B.Cu" "B.Mask" "B.Paste")
			(roundrect_rratio 0.25)
			(net 637 "/DDR5 SODIMM/Control.PWR_EN")
			(pintype "passive")
		)
	)
	(footprint "antmicro-footprints:C_0402_1005Metric"
		(layer "B.Cu")
		(at 140.375501 185.801 90)
		(descr "Capacitor SMD 0402 (1005 Metric), square (rectangular) end terminal, IPC_7351 nominal, (Body size source: IPC-SM-782 page 76, https://www.pcb-3d.com/wordpress/wp-content/uploads/ipc-sm-782a_amendment_1_and_2.pdf)")
		(tags "capacitor 0402")
		(property "Reference" "C39"
			(at 0 1.17 270)
			(layer "B.SilkS")
			(hide yes)
			(effects
				(font
					(size 0.7 0.7)
					(thickness 0.15)
				)
				(justify left bottom mirror)
			)
		)
		(property "Value" "C_100n_0402"
			(at 0 -1.169 270)
			(layer "B.Fab")
			(effects
				(font
					(size 0.7 0.7)
					(thickness 0.15)
				)
				(justify left bottom mirror)
			)
		)
		(property "Datasheet" "https://www.murata.com/products/productdetail?partno=GRM155R61H104KE14%23"
			(at 0 0 90)
			(layer "F.Fab")
			(hide yes)
			(effects
				(font
					(size 1.27 1.27)
					(thickness 0.15)
				)
			)
		)
		(property "Author" "Antmicro"
			(at 326.176501 45.425499 0)
			(layer "B.Fab")
			(hide yes)
			(effects
				(font
					(size 1 1)
					(thickness 0.15)
				)
				(justify mirror)
			)
		)
		(property "Dielectric" "X5R"
			(at 326.176501 45.425499 0)
			(layer "B.Fab")
			(hide yes)
			(effects
				(font
					(size 1 1)
					(thickness 0.15)
				)
				(justify mirror)
			)
		)
		(property "License" "Apache-2.0"
			(at 326.176501 45.425499 0)
			(layer "B.Fab")
			(hide yes)
			(effects
				(font
					(size 1 1)
					(thickness 0.15)
				)
				(justify mirror)
			)
		)
		(property "MPN" "GRM155R61H104KE14D"
			(at 326.176501 45.425499 0)
			(layer "B.Fab")
			(hide yes)
			(effects
				(font
					(size 1 1)
					(thickness 0.15)
				)
				(justify mirror)
			)
		)
		(property "Manufacturer" "Murata"
			(at 326.176501 45.425499 0)
			(layer "B.Fab")
			(hide yes)
			(effects
				(font
					(size 1 1)
					(thickness 0.15)
				)
				(justify mirror)
			)
		)
		(property "Val" "100n"
			(at 326.176501 45.425499 0)
			(layer "B.Fab")
			(hide yes)
			(effects
				(font
					(size 1 1)
					(thickness 0.15)
				)
				(justify mirror)
			)
		)
		(property "Voltage" "50V"
			(at 326.176501 45.425499 0)
			(layer "B.Fab")
			(hide yes)
			(effects
				(font
					(size 1 1)
					(thickness 0.15)
				)
				(justify mirror)
			)
		)
		(sheetname "/FPGA power/")
		(sheetfile "fpga-power.kicad_sch")
		(attr smd)
		(fp_rect
			(start -0.9656 0.4572)
			(end 0.9652 -0.4828)
			(stroke
				(width 0.05)
				(type solid)
			)
			(fill no)
			(layer "B.CrtYd")
		)
		(fp_line
			(start 0.498 -0.248)
			(end -0.5 -0.248)
			(stroke
				(width 0.15)
				(type solid)
			)
			(layer "B.Fab")
		)
		(fp_line
			(start -0.5 -0.248)
			(end -0.5 0.25)
			(stroke
				(width 0.15)
				(type solid)
			)
			(layer "B.Fab")
		)
		(fp_line
			(start 0.498 0.25)
			(end 0.498 -0.248)
			(stroke
				(width 0.15)
				(type solid)
			)
			(layer "B.Fab")
		)
		(fp_line
			(start -0.5 0.25)
			(end 0.498 0.25)
			(stroke
				(width 0.15)
				(type solid)
			)
			(layer "B.Fab")
		)
		(pad "1" smd roundrect
			(at -0.5 0)
			(size 0.6 0.6)
			(layers "B.Cu" "B.Mask" "B.Paste")
			(roundrect_rratio 0.25)
			(net 1 "GND")
			(pintype "passive")
		)
		(pad "2" smd roundrect
			(at 0.498 0 90)
			(size 0.6 0.6)
			(layers "B.Cu" "B.Mask" "B.Paste")
			(roundrect_rratio 0.25)
			(net 200 "+3V3")
			(pintype "passive")
		)
	)
	(footprint "antmicro-footprints:R_0402_1005Metric"
		(layer "B.Cu")
		(at 134.875 186.3 180)
		(descr "Resistor SMD 0402 (1005 Metric), square (rectangular) end terminal, IPC_7351 nominal, (Body size source: IPC-SM-782 page 76, https://www.pcb-3d.com/wordpress/wp-content/uploads/ipc-sm-782a_amendment_1_and_2.pdf)")
		(tags "resistor 0402")
		(property "Reference" "R97"
			(at 0 1.17 0)
			(layer "B.SilkS")
			(hide yes)
			(effects
				(font
					(size 0.7 0.7)
					(thickness 0.15)
				)
				(justify left bottom mirror)
			)
		)
		(property "Value" "R_0R_0402"
			(at 0 -1.169 0)
			(layer "B.Fab")
			(effects
				(font
					(size 0.7 0.7)
					(thickness 0.15)
				)
				(justify left bottom mirror)
			)
		)
		(property "Datasheet" "https://industrial.panasonic.com/cdbs/www-data/pdf/RDA0000/AOA0000C301.pdf"
			(at 0 0 180)
			(layer "F.Fab")
			(hide yes)
			(effects
				(font
					(size 1.27 1.27)
					(thickness 0.15)
				)
			)
		)
		(property "Author" "Antmicro"
			(at 269.75 372.6 0)
			(layer "B.Fab")
			(hide yes)
			(effects
				(font
					(size 1 1)
					(thickness 0.15)
				)
				(justify mirror)
			)
		)
		(property "Current" "1A"
			(at 269.75 372.6 0)
			(layer "B.Fab")
			(hide yes)
			(effects
				(font
					(size 1 1)
					(thickness 0.15)
				)
				(justify mirror)
			)
		)
		(property "License" "Apache-2.0"
			(at 269.75 372.6 0)
			(layer "B.Fab")
			(hide yes)
			(effects
				(font
					(size 1 1)
					(thickness 0.15)
				)
				(justify mirror)
			)
		)
		(property "MPN" "ERJ2GE0R00X"
			(at 269.75 372.6 0)
			(layer "B.Fab")
			(hide yes)
			(effects
				(font
					(size 1 1)
					(thickness 0.15)
				)
				(justify mirror)
			)
		)
		(property "Manufacturer" "Panasonic"
			(at 269.75 372.6 0)
			(layer "B.Fab")
			(hide yes)
			(effects
				(font
					(size 1 1)
					(thickness 0.15)
				)
				(justify mirror)
			)
		)
		(property "Tolerance" ""
			(at 269.75 372.6 0)
			(layer "B.Fab")
			(hide yes)
			(effects
				(font
					(size 1 1)
					(thickness 0.15)
				)
				(justify mirror)
			)
		)
		(property "Val" "0R"
			(at 269.75 372.6 0)
			(layer "B.Fab")
			(hide yes)
			(effects
				(font
					(size 1 1)
					(thickness 0.15)
				)
				(justify mirror)
			)
		)
		(sheetname "/FPGA banks unused/")
		(sheetfile "fpga-bank-13-15.kicad_sch")
		(attr smd)
		(fp_line
			(start 0.9652 0.46)
			(end 0.9652 -0.45)
			(stroke
				(width 0.05)
				(type solid)
			)
			(layer "B.CrtYd")
		)
		(fp_line
			(start 0.9652 -0.45)
			(end -0.95 -0.45)
			(stroke
				(width 0.05)
				(type solid)
			)
			(layer "B.CrtYd")
		)
		(fp_line
			(start -0.95 0.46)
			(end 0.9652 0.46)
			(stroke
				(width 0.05)
				(type solid)
			)
			(layer "B.CrtYd")
		)
		(fp_line
			(start -0.95 -0.45)
			(end -0.95 0.46)
			(stroke
				(width 0.05)
				(type solid)
			)
			(layer "B.CrtYd")
		)
		(fp_line
			(start 0.499 0.25)
			(end 0.499 -0.249)
			(stroke
				(width 0.15)
				(type solid)
			)
			(layer "B.Fab")
		)
		(fp_line
			(start 0.499 -0.249)
			(end -0.5 -0.249)
			(stroke
				(width 0.15)
				(type solid)
			)
			(layer "B.Fab")
		)
		(fp_line
			(start -0.5 0.25)
			(end 0.499 0.25)
			(stroke
				(width 0.15)
				(type solid)
			)
			(layer "B.Fab")
		)
		(fp_line
			(start -0.5 -0.249)
			(end -0.5 0.25)
			(stroke
				(width 0.15)
				(type solid)
			)
			(layer "B.Fab")
		)
		(pad "1" smd roundrect
			(at -0.5 0 90)
			(size 0.6 0.6)
			(layers "B.Cu" "B.Mask" "B.Paste")
			(roundrect_rratio 0.25)
			(net 200 "+3V3")
			(pintype "passive")
		)
		(pad "2" smd roundrect
			(at 0.499 0 180)
			(size 0.6 0.6)
			(layers "B.Cu" "B.Mask" "B.Paste")
			(roundrect_rratio 0.25)
			(net 377 "Net-(R97-Pad2)")
			(pintype "passive")
		)
	)
	(footprint "antmicro-footprints:C_0402_1005Metric"
		(layer "B.Cu")
		(at 145.375501 178.801 90)
		(descr "Capacitor SMD 0402 (1005 Metric), square (rectangular) end terminal, IPC_7351 nominal, (Body size source: IPC-SM-782 page 76, https://www.pcb-3d.com/wordpress/wp-content/uploads/ipc-sm-782a_amendment_1_and_2.pdf)")
		(tags "capacitor 0402")
		(property "Reference" "C21"
			(at 0 1.17 270)
			(layer "B.SilkS")
			(hide yes)
			(effects
				(font
					(size 0.7 0.7)
					(thickness 0.15)
				)
				(justify left bottom mirror)
			)
		)
		(property "Value" "C_100n_0402"
			(at 0 -1.169 270)
			(layer "B.Fab")
			(effects
				(font
					(size 0.7 0.7)
					(thickness 0.15)
				)
				(justify left bottom mirror)
			)
		)
		(property "Datasheet" "https://www.murata.com/products/productdetail?partno=GRM155R61H104KE14%23"
			(at 0 0 90)
			(layer "F.Fab")
			(hide yes)
			(effects
				(font
					(size 1.27 1.27)
					(thickness 0.15)
				)
			)
		)
		(property "Author" "Antmicro"
			(at 324.176501 33.425499 0)
			(layer "B.Fab")
			(hide yes)
			(effects
				(font
					(size 1 1)
					(thickness 0.15)
				)
				(justify mirror)
			)
		)
		(property "Dielectric" "X5R"
			(at 324.176501 33.425499 0)
			(layer "B.Fab")
			(hide yes)
			(effects
				(font
					(size 1 1)
					(thickness 0.15)
				)
				(justify mirror)
			)
		)
		(property "License" "Apache-2.0"
			(at 324.176501 33.425499 0)
			(layer "B.Fab")
			(hide yes)
			(effects
				(font
					(size 1 1)
					(thickness 0.15)
				)
				(justify mirror)
			)
		)
		(property "MPN" "GRM155R61H104KE14D"
			(at 324.176501 33.425499 0)
			(layer "B.Fab")
			(hide yes)
			(effects
				(font
					(size 1 1)
					(thickness 0.15)
				)
				(justify mirror)
			)
		)
		(property "Manufacturer" "Murata"
			(at 324.176501 33.425499 0)
			(layer "B.Fab")
			(hide yes)
			(effects
				(font
					(size 1 1)
					(thickness 0.15)
				)
				(justify mirror)
			)
		)
		(property "Val" "100n"
			(at 324.176501 33.425499 0)
			(layer "B.Fab")
			(hide yes)
			(effects
				(font
					(size 1 1)
					(thickness 0.15)
				)
				(justify mirror)
			)
		)
		(property "Voltage" "50V"
			(at 324.176501 33.425499 0)
			(layer "B.Fab")
			(hide yes)
			(effects
				(font
					(size 1 1)
					(thickness 0.15)
				)
				(justify mirror)
			)
		)
		(sheetname "/FPGA power/")
		(sheetfile "fpga-power.kicad_sch")
		(attr smd)
		(fp_rect
			(start -0.9656 0.4572)
			(end 0.9652 -0.4828)
			(stroke
				(width 0.05)
				(type solid)
			)
			(fill no)
			(layer "B.CrtYd")
		)
		(fp_line
			(start 0.498 -0.248)
			(end -0.5 -0.248)
			(stroke
				(width 0.15)
				(type solid)
			)
			(layer "B.Fab")
		)
		(fp_line
			(start -0.5 -0.248)
			(end -0.5 0.25)
			(stroke
				(width 0.15)
				(type solid)
			)
			(layer "B.Fab")
		)
		(fp_line
			(start 0.498 0.25)
			(end 0.498 -0.248)
			(stroke
				(width 0.15)
				(type solid)
			)
			(layer "B.Fab")
		)
		(fp_line
			(start -0.5 0.25)
			(end 0.498 0.25)
			(stroke
				(width 0.15)
				(type solid)
			)
			(layer "B.Fab")
		)
		(pad "1" smd roundrect
			(at -0.5 0)
			(size 0.6 0.6)
			(layers "B.Cu" "B.Mask" "B.Paste")
			(roundrect_rratio 0.25)
			(net 1 "GND")
			(pintype "passive")
		)
		(pad "2" smd roundrect
			(at 0.498 0 90)
			(size 0.6 0.6)
			(layers "B.Cu" "B.Mask" "B.Paste")
			(roundrect_rratio 0.25)
			(net 200 "+3V3")
			(pintype "passive")
		)
	)
	(footprint "antmicro-footprints:C_0402_1005Metric"
		(layer "B.Cu")
		(at 150.875501 166.301)
		(descr "Capacitor SMD 0402 (1005 Metric), square (rectangular) end terminal, IPC_7351 nominal, (Body size source: IPC-SM-782 page 76, https://www.pcb-3d.com/wordpress/wp-content/uploads/ipc-sm-782a_amendment_1_and_2.pdf)")
		(tags "capacitor 0402")
		(property "Reference" "C93"
			(at 0 1.17 180)
			(layer "B.SilkS")
			(hide yes)
			(effects
				(font
					(size 0.7 0.7)
					(thickness 0.15)
				)
				(justify left bottom mirror)
			)
		)
		(property "Value" "C_100n_0402"
			(at 0 -1.169 180)
			(layer "B.Fab")
			(effects
				(font
					(size 0.7 0.7)
					(thickness 0.15)
				)
				(justify left bottom mirror)
			)
		)
		(property "Datasheet" "https://www.murata.com/products/productdetail?partno=GRM155R61H104KE14%23"
			(at 0 0 0)
			(layer "F.Fab")
			(hide yes)
			(effects
				(font
					(size 1.27 1.27)
					(thickness 0.15)
				)
			)
		)
		(property "Author" "Antmicro"
			(at 0 0 0)
			(layer "B.Fab")
			(hide yes)
			(effects
				(font
					(size 1 1)
					(thickness 0.15)
				)
				(justify mirror)
			)
		)
		(property "Dielectric" "X5R"
			(at 0 0 0)
			(layer "B.Fab")
			(hide yes)
			(effects
				(font
					(size 1 1)
					(thickness 0.15)
				)
				(justify mirror)
			)
		)
		(property "License" "Apache-2.0"
			(at 0 0 0)
			(layer "B.Fab")
			(hide yes)
			(effects
				(font
					(size 1 1)
					(thickness 0.15)
				)
				(justify mirror)
			)
		)
		(property "MPN" "GRM155R61H104KE14D"
			(at 0 0 0)
			(layer "B.Fab")
			(hide yes)
			(effects
				(font
					(size 1 1)
					(thickness 0.15)
				)
				(justify mirror)
			)
		)
		(property "Manufacturer" "Murata"
			(at 0 0 0)
			(layer "B.Fab")
			(hide yes)
			(effects
				(font
					(size 1 1)
					(thickness 0.15)
				)
				(justify mirror)
			)
		)
		(property "Val" "100n"
			(at 0 0 0)
			(layer "B.Fab")
			(hide yes)
			(effects
				(font
					(size 1 1)
					(thickness 0.15)
				)
				(justify mirror)
			)
		)
		(property "Voltage" "50V"
			(at 0 0 0)
			(layer "B.Fab")
			(hide yes)
			(effects
				(font
					(size 1 1)
					(thickness 0.15)
				)
				(justify mirror)
			)
		)
		(sheetname "/FPGA power/")
		(sheetfile "fpga-power.kicad_sch")
		(attr smd)
		(fp_rect
			(start -0.9656 0.4572)
			(end 0.9652 -0.4828)
			(stroke
				(width 0.05)
				(type solid)
			)
			(fill no)
			(layer "B.CrtYd")
		)
		(fp_line
			(start -0.5 -0.248)
			(end -0.5 0.25)
			(stroke
				(width 0.15)
				(type solid)
			)
			(layer "B.Fab")
		)
		(fp_line
			(start -0.5 0.25)
			(end 0.498 0.25)
			(stroke
				(width 0.15)
				(type solid)
			)
			(layer "B.Fab")
		)
		(fp_line
			(start 0.498 -0.248)
			(end -0.5 -0.248)
			(stroke
				(width 0.15)
				(type solid)
			)
			(layer "B.Fab")
		)
		(fp_line
			(start 0.498 0.25)
			(end 0.498 -0.248)
			(stroke
				(width 0.15)
				(type solid)
			)
			(layer "B.Fab")
		)
		(pad "1" smd roundrect
			(at -0.5 0 270)
			(size 0.6 0.6)
			(layers "B.Cu" "B.Mask" "B.Paste")
			(roundrect_rratio 0.25)
			(net 1 "GND")
			(pintype "passive")
		)
		(pad "2" smd roundrect
			(at 0.498 0)
			(size 0.6 0.6)
			(layers "B.Cu" "B.Mask" "B.Paste")
			(roundrect_rratio 0.25)
			(net 206 "+1V1")
			(pintype "passive")
		)
	)
)
